(kicad_pcb
	(version 20260206)
	(generator "pcbnew")
	(generator_version "10.0")
	(general
		(thickness 1.6)
		(legacy_teardrops no)
	)
	(paper "A4")
	(title_block
		(title "04192023_DAF0TMB3IC0_F0TG_MB_C_brd_V02_OCP.brd")
		(comment 1 "Grand Teton / footprint 3955 of 8354 (U25), pads 5999-6102 of 6102")
	)
	(layers
		(0 "F.Cu" signal "TOP")
		(4 "In1.Cu" signal "GND")
		(6 "In2.Cu" signal "IN1")
		(8 "In3.Cu" signal "GND1")
		(10 "In4.Cu" signal "IN2")
		(12 "In5.Cu" signal "GND2")
		(14 "In6.Cu" signal "IN3")
		(16 "In7.Cu" signal "GND3")
		(18 "In8.Cu" signal "VCC")
		(20 "In9.Cu" signal "VCC1")
		(22 "In10.Cu" signal "GND4")
		(24 "In11.Cu" signal "IN4")
		(26 "In12.Cu" signal "GND5")
		(28 "In13.Cu" signal "IN5")
		(30 "In14.Cu" signal "GND6")
		(32 "In15.Cu" signal "IN6")
		(34 "In16.Cu" signal "GND7")
		(2 "B.Cu" signal "BOTTOM")
		(9 "F.Adhes" user "F.Adhesive")
		(11 "B.Adhes" user "B.Adhesive")
		(13 "F.Paste" user "Package Geometry/Pastemask Top")
		(15 "B.Paste" user "Package Geometry/Pastemask Bottom")
		(5 "F.SilkS" user "Ref Des/Silkscreen Top")
		(7 "B.SilkS" user "Ref Des/Silkscreen Bottom")
		(1 "F.Mask" user "Board Geometry/Soldermask Top")
		(3 "B.Mask" user "Board Geometry/Soldermask Bottom")
		(17 "Dwgs.User" user "User.Drawings")
		(19 "Cmts.User" user "User.Comments")
		(21 "Eco1.User" user "User.Eco1")
		(23 "Eco2.User" user "User.Eco2")
		(25 "Edge.Cuts" user "Board Geometry/Outline")
		(27 "Margin" user)
		(31 "F.CrtYd" user "Package Geometry/Place Bound Top")
		(29 "B.CrtYd" user "Package Geometry/Place Bound Bottom")
		(35 "F.Fab" user "Ref Des/Assembly Top")
		(33 "B.Fab" user "Ref Des/Assembly Bottom")
	)
	(footprint ""
		(layer "F.Cu")
		(at 359.867962 -258.880102 180)
		(property "Reference" "U25"
			(at -45.78477 -62.086744 0)
			(unlocked yes)
			(layer "F.SilkS")
			(effects
				(font
					(size 0.7874 0.5842)
					(thickness 0.1524)
				)
			)
		)
		(property "Value" ""
			(at 0 0 180)
			(layer "F.Fab")
			(effects
				(font
					(size 1.27 1.27)
				)
			)
		)
		(duplicate_pad_numbers_are_jumpers no)
		(pad "W44" smd circle
			(at 5.32003 -22.23008 180)
			(size 0.450088 0.450088)
			(layers "F.Cu" "F.Mask" "F.Paste")
			(net "PVDDCR_CPU0_P0")
		)
		(pad "W45" smd circle
			(at 6.260084 -22.23008 180)
			(size 0.450088 0.450088)
			(layers "F.Cu" "F.Mask" "F.Paste")
			(net "GND")
		)
		(pad "W46" smd circle
			(at 7.199884 -22.23008 180)
			(size 0.450088 0.450088)
			(layers "F.Cu" "F.Mask" "F.Paste")
			(net "PVDDCR_CPU0_P0")
		)
		(pad "W47" smd circle
			(at 8.139938 -22.23008 180)
			(size 0.450088 0.450088)
			(layers "F.Cu" "F.Mask" "F.Paste")
			(net "PVDDCR_CPU0_P0")
		)
		(pad "W48" smd circle
			(at 9.079992 -22.23008 180)
			(size 0.450088 0.450088)
			(layers "F.Cu" "F.Mask" "F.Paste")
			(net "GND")
		)
		(pad "W49" smd circle
			(at 10.020046 -22.23008 180)
			(size 0.450088 0.450088)
			(layers "F.Cu" "F.Mask" "F.Paste")
			(net "GMI_CPU1_G3_CPU0_G1_TX_DN<9>")
		)
		(pad "W50" smd circle
			(at 10.9601 -22.23008 180)
			(size 0.450088 0.450088)
			(layers "F.Cu" "F.Mask" "F.Paste")
			(net "GMI_CPU1_G3_CPU0_G1_TX_DP<9>")
		)
		(pad "W51" smd circle
			(at 11.8999 -22.23008 180)
			(size 0.450088 0.450088)
			(layers "F.Cu" "F.Mask" "F.Paste")
			(net "GND")
		)
		(pad "W52" smd circle
			(at 12.839954 -22.23008 180)
			(size 0.450088 0.450088)
			(layers "F.Cu" "F.Mask" "F.Paste")
			(net "GMI_CPU1_G3_CPU0_G1_TX_DN<13>")
		)
		(pad "W53" smd circle
			(at 13.780008 -22.23008 180)
			(size 0.450088 0.450088)
			(layers "F.Cu" "F.Mask" "F.Paste")
			(net "GMI_CPU1_G3_CPU0_G1_TX_DP<13>")
		)
		(pad "W54" smd circle
			(at 14.720062 -22.23008 180)
			(size 0.450088 0.450088)
			(layers "F.Cu" "F.Mask" "F.Paste")
			(net "GND")
		)
		(pad "W55" smd circle
			(at 15.660116 -22.23008 180)
			(size 0.450088 0.450088)
			(layers "F.Cu" "F.Mask" "F.Paste")
			(net "M_C_CPU0_SA_DQ<19>")
		)
		(pad "W56" smd circle
			(at 16.599916 -22.23008 180)
			(size 0.450088 0.450088)
			(layers "F.Cu" "F.Mask" "F.Paste")
			(net "GND")
		)
		(pad "W57" smd circle
			(at 17.53997 -22.23008 180)
			(size 0.450088 0.450088)
			(layers "F.Cu" "F.Mask" "F.Paste")
			(net "M_C_CPU0_SA_DQS_DP<2>")
		)
		(pad "W58" smd circle
			(at 18.480024 -22.23008 180)
			(size 0.450088 0.450088)
			(layers "F.Cu" "F.Mask" "F.Paste")
			(net "GND")
		)
		(pad "W59" smd circle
			(at 19.420078 -22.23008 180)
			(size 0.450088 0.450088)
			(layers "F.Cu" "F.Mask" "F.Paste")
			(net "M_D_CPU0_SA_DQ<19>")
		)
		(pad "W60" smd circle
			(at 20.359878 -22.23008 180)
			(size 0.450088 0.450088)
			(layers "F.Cu" "F.Mask" "F.Paste")
			(net "M_D_CPU0_SA_DQS_DP<2>")
		)
		(pad "W61" smd circle
			(at 21.299932 -22.23008 180)
			(size 0.450088 0.450088)
			(layers "F.Cu" "F.Mask" "F.Paste")
			(net "GND")
		)
		(pad "W62" smd circle
			(at 22.239986 -22.23008 180)
			(size 0.450088 0.450088)
			(layers "F.Cu" "F.Mask" "F.Paste")
			(net "M_B_CPU0_SA_DQ<19>")
		)
		(pad "W63" smd circle
			(at 23.18004 -22.23008 180)
			(size 0.450088 0.450088)
			(layers "F.Cu" "F.Mask" "F.Paste")
			(net "GND")
		)
		(pad "W64" smd circle
			(at 24.120094 -22.23008 180)
			(size 0.450088 0.450088)
			(layers "F.Cu" "F.Mask" "F.Paste")
			(net "M_B_CPU0_SA_DQS_DP<2>")
		)
		(pad "W65" smd circle
			(at 25.059894 -22.23008 180)
			(size 0.450088 0.450088)
			(layers "F.Cu" "F.Mask" "F.Paste")
			(net "GND")
		)
		(pad "W66" smd circle
			(at 25.999948 -22.23008 180)
			(size 0.450088 0.450088)
			(layers "F.Cu" "F.Mask" "F.Paste")
			(net "M_F_CPU0_SA_DQ<19>")
		)
		(pad "W67" smd circle
			(at 26.940002 -22.23008 180)
			(size 0.450088 0.450088)
			(layers "F.Cu" "F.Mask" "F.Paste")
			(net "M_F_CPU0_SA_DQS_DP<2>")
		)
		(pad "W68" smd circle
			(at 27.880056 -22.23008 180)
			(size 0.450088 0.450088)
			(layers "F.Cu" "F.Mask" "F.Paste")
			(net "GND")
		)
		(pad "W69" smd circle
			(at 28.82011 -22.23008 180)
			(size 0.450088 0.450088)
			(layers "F.Cu" "F.Mask" "F.Paste")
			(net "M_E_CPU0_SA_DQ<19>")
		)
		(pad "W70" smd circle
			(at 29.75991 -22.23008 180)
			(size 0.450088 0.450088)
			(layers "F.Cu" "F.Mask" "F.Paste")
			(net "GND")
		)
		(pad "W71" smd circle
			(at 30.699964 -22.23008 180)
			(size 0.450088 0.450088)
			(layers "F.Cu" "F.Mask" "F.Paste")
			(net "M_E_CPU0_SA_DQS_DP<2>")
		)
		(pad "W72" smd circle
			(at 31.640018 -22.23008 180)
			(size 0.450088 0.450088)
			(layers "F.Cu" "F.Mask" "F.Paste")
			(net "GND")
		)
		(pad "W73" smd circle
			(at 32.580072 -22.23008 180)
			(size 0.450088 0.450088)
			(layers "F.Cu" "F.Mask" "F.Paste")
			(net "M_A_CPU0_SA_DQ<19>")
		)
		(pad "W74" smd circle
			(at 33.519872 -22.23008 180)
			(size 0.450088 0.450088)
			(layers "F.Cu" "F.Mask" "F.Paste")
			(net "M_A_CPU0_SA_DQS_DP<2>")
		)
		(pad "W75" smd circle
			(at 34.459926 -22.23008 180)
			(size 0.450088 0.450088)
			(layers "F.Cu" "F.Mask" "F.Paste")
			(net "GND")
		)
		(pad "Y2" smd circle
			(at -33.690052 -21.420074 180)
			(size 0.450088 0.450088)
			(layers "F.Cu" "F.Mask" "F.Paste")
			(net "M_G_CPU0_SA_DQS_DN<2>")
		)
		(pad "Y3" smd circle
			(at -32.749998 -21.420074 180)
			(size 0.450088 0.450088)
			(layers "F.Cu" "F.Mask" "F.Paste")
			(net "GND")
		)
		(pad "Y4" smd circle
			(at -31.809944 -21.420074 180)
			(size 0.450088 0.450088)
			(layers "F.Cu" "F.Mask" "F.Paste")
			(net "M_G_CPU0_SA_DQS_DN<7>")
		)
		(pad "Y5" smd circle
			(at -30.86989 -21.420074 180)
			(size 0.450088 0.450088)
			(layers "F.Cu" "F.Mask" "F.Paste")
			(net "PVDDCR_SOC_P0")
		)
		(pad "Y6" smd circle
			(at -29.93009 -21.420074 180)
			(size 0.450088 0.450088)
			(layers "F.Cu" "F.Mask" "F.Paste")
			(net "M_K_CPU0_SA_DQS_DN<2>")
		)
		(pad "Y7" smd circle
			(at -28.990036 -21.420074 180)
			(size 0.450088 0.450088)
			(layers "F.Cu" "F.Mask" "F.Paste")
			(net "M_K_CPU0_SA_DQS_DN<7>")
		)
		(pad "Y8" smd circle
			(at -28.049982 -21.420074 180)
			(size 0.450088 0.450088)
			(layers "F.Cu" "F.Mask" "F.Paste")
			(net "GND")
		)
		(pad "Y9" smd circle
			(at -27.109928 -21.420074 180)
			(size 0.450088 0.450088)
			(layers "F.Cu" "F.Mask" "F.Paste")
			(net "M_L_CPU0_SA_DQS_DN<2>")
		)
		(pad "Y10" smd circle
			(at -26.170128 -21.420074 180)
			(size 0.450088 0.450088)
			(layers "F.Cu" "F.Mask" "F.Paste")
			(net "GND")
		)
		(pad "Y11" smd circle
			(at -25.230074 -21.420074 180)
			(size 0.450088 0.450088)
			(layers "F.Cu" "F.Mask" "F.Paste")
			(net "M_L_CPU0_SA_DQS_DN<7>")
		)
		(pad "Y12" smd circle
			(at -24.29002 -21.420074 180)
			(size 0.450088 0.450088)
			(layers "F.Cu" "F.Mask" "F.Paste")
			(net "PVDDCR_SOC_P0")
		)
		(pad "Y13" smd circle
			(at -23.349966 -21.420074 180)
			(size 0.450088 0.450088)
			(layers "F.Cu" "F.Mask" "F.Paste")
			(net "M_H_CPU0_SA_DQS_DN<2>")
		)
		(pad "Y14" smd circle
			(at -22.409912 -21.420074 180)
			(size 0.450088 0.450088)
			(layers "F.Cu" "F.Mask" "F.Paste")
			(net "M_H_CPU0_SA_DQS_DN<7>")
		)
		(pad "Y15" smd circle
			(at -21.470112 -21.420074 180)
			(size 0.450088 0.450088)
			(layers "F.Cu" "F.Mask" "F.Paste")
			(net "GND")
		)
		(pad "Y16" smd circle
			(at -20.530058 -21.420074 180)
			(size 0.450088 0.450088)
			(layers "F.Cu" "F.Mask" "F.Paste")
			(net "M_J_CPU0_SA_DQS_DN<2>")
		)
		(pad "Y17" smd circle
			(at -19.590004 -21.420074 180)
			(size 0.450088 0.450088)
			(layers "F.Cu" "F.Mask" "F.Paste")
			(net "GND")
		)
		(pad "Y18" smd circle
			(at -18.64995 -21.420074 180)
			(size 0.450088 0.450088)
			(layers "F.Cu" "F.Mask" "F.Paste")
			(net "M_J_CPU0_SA_DQS_DN<7>")
		)
		(pad "Y19" smd circle
			(at -17.709896 -21.420074 180)
			(size 0.450088 0.450088)
			(layers "F.Cu" "F.Mask" "F.Paste")
			(net "PVDDCR_SOC_P0")
		)
		(pad "Y20" smd circle
			(at -16.770096 -21.420074 180)
			(size 0.450088 0.450088)
			(layers "F.Cu" "F.Mask" "F.Paste")
			(net "M_I_CPU0_SA_DQS_DN<2>")
		)
		(pad "Y21" smd circle
			(at -15.830042 -21.420074 180)
			(size 0.450088 0.450088)
			(layers "F.Cu" "F.Mask" "F.Paste")
			(net "M_I_CPU0_SA_DQS_DN<7>")
		)
		(pad "Y22" smd circle
			(at -14.889988 -21.420074 180)
			(size 0.450088 0.450088)
			(layers "F.Cu" "F.Mask" "F.Paste")
			(net "GND")
		)
		(pad "Y23" smd circle
			(at -13.949934 -21.420074 180)
			(size 0.450088 0.450088)
			(layers "F.Cu" "F.Mask" "F.Paste")
			(net "GND")
		)
		(pad "Y24" smd circle
			(at -13.00988 -21.420074 180)
			(size 0.450088 0.450088)
			(layers "F.Cu" "F.Mask" "F.Paste")
			(net "GND")
		)
		(pad "Y25" smd circle
			(at -12.07008 -21.420074 180)
			(size 0.450088 0.450088)
			(layers "F.Cu" "F.Mask" "F.Paste")
			(net "GND")
		)
		(pad "Y26" smd circle
			(at -11.130026 -21.420074 180)
			(size 0.450088 0.450088)
			(layers "F.Cu" "F.Mask" "F.Paste")
			(net "GND")
		)
		(pad "Y27" smd circle
			(at -10.189972 -21.420074 180)
			(size 0.450088 0.450088)
			(layers "F.Cu" "F.Mask" "F.Paste")
			(net "GND")
		)
		(pad "Y28" smd circle
			(at -9.249918 -21.420074 180)
			(size 0.450088 0.450088)
			(layers "F.Cu" "F.Mask" "F.Paste")
			(net "GND")
		)
		(pad "Y29" smd circle
			(at -8.310118 -21.420074 180)
			(size 0.450088 0.450088)
			(layers "F.Cu" "F.Mask" "F.Paste")
			(net "TP_CPU0_TEST5_CCD11")
		)
		(pad "Y30" smd circle
			(at -7.370064 -21.420074 180)
			(size 0.450088 0.450088)
			(layers "F.Cu" "F.Mask" "F.Paste")
			(net "TP_CPU0_TEST5_CCD3")
		)
		(pad "Y31" smd circle
			(at -6.43001 -21.420074 180)
			(size 0.450088 0.450088)
			(layers "F.Cu" "F.Mask" "F.Paste")
			(net "GND")
		)
		(pad "Y32" smd circle
			(at -5.489956 -21.420074 180)
			(size 0.450088 0.450088)
			(layers "F.Cu" "F.Mask" "F.Paste")
			(net "GND")
		)
		(pad "Y33" smd circle
			(at -4.549902 -21.420074 180)
			(size 0.450088 0.450088)
			(layers "F.Cu" "F.Mask" "F.Paste")
			(net "GND")
		)
		(pad "Y34" smd circle
			(at -3.610102 -21.420074 180)
			(size 0.450088 0.450088)
			(layers "F.Cu" "F.Mask" "F.Paste")
			(net "GND")
		)
		(pad "Y35" smd circle
			(at -2.670048 -21.420074 180)
			(size 0.450088 0.450088)
			(layers "F.Cu" "F.Mask" "F.Paste")
			(net "PVDDCR_CPU0_P0")
		)
		(pad "Y36" smd circle
			(at -1.729994 -21.420074 180)
			(size 0.450088 0.450088)
			(layers "F.Cu" "F.Mask" "F.Paste")
			(net "PVDDCR_CPU0_P0")
		)
		(pad "Y37" smd circle
			(at -0.78994 -21.420074 180)
			(size 0.450088 0.450088)
			(layers "F.Cu" "F.Mask" "F.Paste")
			(net "GND")
		)
		(pad "Y39" smd circle
			(at 1.089914 -21.420074 180)
			(size 0.450088 0.450088)
			(layers "F.Cu" "F.Mask" "F.Paste")
			(net "GND")
		)
		(pad "Y40" smd circle
			(at 2.029968 -21.420074 180)
			(size 0.450088 0.450088)
			(layers "F.Cu" "F.Mask" "F.Paste")
			(net "PVDDCR_CPU0_P0")
		)
		(pad "Y41" smd circle
			(at 2.970022 -21.420074 180)
			(size 0.450088 0.450088)
			(layers "F.Cu" "F.Mask" "F.Paste")
			(net "PVDDCR_CPU0_P0")
		)
		(pad "Y42" smd circle
			(at 3.910076 -21.420074 180)
			(size 0.450088 0.450088)
			(layers "F.Cu" "F.Mask" "F.Paste")
			(net "GND")
		)
		(pad "Y43" smd circle
			(at 4.849876 -21.420074 180)
			(size 0.450088 0.450088)
			(layers "F.Cu" "F.Mask" "F.Paste")
			(net "GND")
		)
		(pad "Y44" smd circle
			(at 5.78993 -21.420074 180)
			(size 0.450088 0.450088)
			(layers "F.Cu" "F.Mask" "F.Paste")
			(net "GND")
		)
		(pad "Y45" smd circle
			(at 6.729984 -21.420074 180)
			(size 0.450088 0.450088)
			(layers "F.Cu" "F.Mask" "F.Paste")
			(net "GND")
		)
		(pad "Y46" smd circle
			(at 7.670038 -21.420074 180)
			(size 0.450088 0.450088)
			(layers "F.Cu" "F.Mask" "F.Paste")
			(net "TP_CPU0_TEST6_CCD3")
		)
		(pad "Y47" smd circle
			(at 8.610092 -21.420074 180)
			(size 0.450088 0.450088)
			(layers "F.Cu" "F.Mask" "F.Paste")
			(net "TP_CPU0_TEST5_CCD8")
		)
		(pad "Y48" smd circle
			(at 9.549892 -21.420074 180)
			(size 0.450088 0.450088)
			(layers "F.Cu" "F.Mask" "F.Paste")
			(net "GND")
		)
		(pad "Y49" smd circle
			(at 10.489946 -21.420074 180)
			(size 0.450088 0.450088)
			(layers "F.Cu" "F.Mask" "F.Paste")
			(net "GND")
		)
		(pad "Y50" smd circle
			(at 11.43 -21.420074 180)
			(size 0.450088 0.450088)
			(layers "F.Cu" "F.Mask" "F.Paste")
			(net "GND")
		)
		(pad "Y51" smd circle
			(at 12.370054 -21.420074 180)
			(size 0.450088 0.450088)
			(layers "F.Cu" "F.Mask" "F.Paste")
			(net "GND")
		)
		(pad "Y52" smd circle
			(at 13.310108 -21.420074 180)
			(size 0.450088 0.450088)
			(layers "F.Cu" "F.Mask" "F.Paste")
			(net "GND")
		)
		(pad "Y53" smd circle
			(at 14.249908 -21.420074 180)
			(size 0.450088 0.450088)
			(layers "F.Cu" "F.Mask" "F.Paste")
			(net "GND")
		)
		(pad "Y54" smd circle
			(at 15.189962 -21.420074 180)
			(size 0.450088 0.450088)
			(layers "F.Cu" "F.Mask" "F.Paste")
			(net "GND")
		)
		(pad "Y55" smd circle
			(at 16.130016 -21.420074 180)
			(size 0.450088 0.450088)
			(layers "F.Cu" "F.Mask" "F.Paste")
			(net "M_C_CPU0_SA_DQS_DN<7>")
		)
		(pad "Y56" smd circle
			(at 17.07007 -21.420074 180)
			(size 0.450088 0.450088)
			(layers "F.Cu" "F.Mask" "F.Paste")
			(net "M_C_CPU0_SA_DQS_DN<2>")
		)
		(pad "Y57" smd circle
			(at 18.010124 -21.420074 180)
			(size 0.450088 0.450088)
			(layers "F.Cu" "F.Mask" "F.Paste")
			(net "PVDDIO_P0")
		)
		(pad "Y58" smd circle
			(at 18.949924 -21.420074 180)
			(size 0.450088 0.450088)
			(layers "F.Cu" "F.Mask" "F.Paste")
			(net "M_D_CPU0_SA_DQS_DN<7>")
		)
		(pad "Y59" smd circle
			(at 19.889978 -21.420074 180)
			(size 0.450088 0.450088)
			(layers "F.Cu" "F.Mask" "F.Paste")
			(net "GND")
		)
		(pad "Y60" smd circle
			(at 20.830032 -21.420074 180)
			(size 0.450088 0.450088)
			(layers "F.Cu" "F.Mask" "F.Paste")
			(net "M_D_CPU0_SA_DQS_DN<2>")
		)
		(pad "Y61" smd circle
			(at 21.770086 -21.420074 180)
			(size 0.450088 0.450088)
			(layers "F.Cu" "F.Mask" "F.Paste")
			(net "GND")
		)
		(pad "Y62" smd circle
			(at 22.709886 -21.420074 180)
			(size 0.450088 0.450088)
			(layers "F.Cu" "F.Mask" "F.Paste")
			(net "M_B_CPU0_SA_DQS_DN<7>")
		)
		(pad "Y63" smd circle
			(at 23.64994 -21.420074 180)
			(size 0.450088 0.450088)
			(layers "F.Cu" "F.Mask" "F.Paste")
			(net "M_B_CPU0_SA_DQS_DN<2>")
		)
		(pad "Y64" smd circle
			(at 24.589994 -21.420074 180)
			(size 0.450088 0.450088)
			(layers "F.Cu" "F.Mask" "F.Paste")
			(net "PVDDIO_P0")
		)
		(pad "Y65" smd circle
			(at 25.530048 -21.420074 180)
			(size 0.450088 0.450088)
			(layers "F.Cu" "F.Mask" "F.Paste")
			(net "M_F_CPU0_SA_DQS_DN<7>")
		)
		(pad "Y66" smd circle
			(at 26.470102 -21.420074 180)
			(size 0.450088 0.450088)
			(layers "F.Cu" "F.Mask" "F.Paste")
			(net "GND")
		)
		(pad "Y67" smd circle
			(at 27.409902 -21.420074 180)
			(size 0.450088 0.450088)
			(layers "F.Cu" "F.Mask" "F.Paste")
			(net "M_F_CPU0_SA_DQS_DN<2>")
		)
		(pad "Y68" smd circle
			(at 28.349956 -21.420074 180)
			(size 0.450088 0.450088)
			(layers "F.Cu" "F.Mask" "F.Paste")
			(net "GND")
		)
		(pad "Y69" smd circle
			(at 29.29001 -21.420074 180)
			(size 0.450088 0.450088)
			(layers "F.Cu" "F.Mask" "F.Paste")
			(net "M_E_CPU0_SA_DQS_DN<7>")
		)
		(pad "Y70" smd circle
			(at 30.230064 -21.420074 180)
			(size 0.450088 0.450088)
			(layers "F.Cu" "F.Mask" "F.Paste")
			(net "M_E_CPU0_SA_DQS_DN<2>")
		)
		(pad "Y71" smd circle
			(at 31.170118 -21.420074 180)
			(size 0.450088 0.450088)
			(layers "F.Cu" "F.Mask" "F.Paste")
			(net "PVDDIO_P0")
		)
		(pad "Y72" smd circle
			(at 32.109918 -21.420074 180)
			(size 0.450088 0.450088)
			(layers "F.Cu" "F.Mask" "F.Paste")
			(net "M_A_CPU0_SA_DQS_DN<7>")
		)
		(pad "Y73" smd circle
			(at 33.049972 -21.420074 180)
			(size 0.450088 0.450088)
			(layers "F.Cu" "F.Mask" "F.Paste")
			(net "GND")
		)
		(pad "Y74" smd circle
			(at 33.990026 -21.420074 180)
			(size 0.450088 0.450088)
			(layers "F.Cu" "F.Mask" "F.Paste")
			(net "M_A_CPU0_SA_DQS_DN<2>")
		)
	)
)
